# BASEBOARD_FAB2 (Tioga Pass) — schematic netlist excerpt (pin names and nets, part order shuffled) for the footprints in the layout excerpt that follows; sources: Cadence DE-HDL packaged netlist, KiCad conversion of Wiwynn_Tioga_Pass_MB.brd

R7G17  RES  0.0 5% CHIP  pkg 0402  page 189 : A = JTAG_BMC_TDO ; B = JTAG_TDO
CF22  SC22P50V2JN-4GP  5%  pkg SMD-BCG  page 226 : \1\ = VR_PVDDQ_KLM_AIREF2 ; \2\ = ISENSE_PVDDQ_KLM_PH2_IMON
R12W15  665KR2B-GP  0.1%  pkg SMD-RG2  page 197 : \1\ = VR_PVDDQ_GHJ_AIINSEN ; \2\ = VR_PVDDQ_GHJ_VINSEN

(kicad_pcb
	(version 20260206)
	(generator "pcbnew")
	(generator_version "10.0")
	(general
		(thickness 1.6)
		(legacy_teardrops no)
	)
	(paper "A4")
	(title_block
		(title "Wiwynn_Tioga_Pass_MB.brd")
		(comment 1 "Tioga Pass / footprints 1353-1355 of 4770")
	)
	(layers
		(0 "F.Cu" signal "TOP")
		(4 "In1.Cu" signal "L2GND")
		(6 "In2.Cu" signal "L3")
		(8 "In3.Cu" signal "L4GND")
		(10 "In4.Cu" signal "L5")
		(12 "In5.Cu" signal "L6GND")
		(14 "In6.Cu" signal "L7VCC")
		(16 "In7.Cu" signal "L8VCC")
		(18 "In8.Cu" signal "L9GND")
		(20 "In9.Cu" signal "L10")
		(22 "In10.Cu" signal "L11GND")
		(24 "In11.Cu" signal "L12")
		(26 "In12.Cu" signal "L13GND")
		(2 "B.Cu" signal "BOTTOM")
		(9 "F.Adhes" user "F.Adhesive")
		(11 "B.Adhes" user "B.Adhesive")
		(13 "F.Paste" user "Package Geometry/Pastemask Top")
		(15 "B.Paste" user "Package Geometry/Pastemask Bottom")
		(5 "F.SilkS" user "Ref Des/Silkscreen Top")
		(7 "B.SilkS" user "Ref Des/Silkscreen Bottom")
		(1 "F.Mask" user "Board Geometry/Soldermask Top")
		(3 "B.Mask" user "Board Geometry/Soldermask Bottom")
		(17 "Dwgs.User" user "User.Drawings")
		(19 "Cmts.User" user "User.Comments")
		(21 "Eco1.User" user "User.Eco1")
		(23 "Eco2.User" user "User.Eco2")
		(25 "Edge.Cuts" user "Board Geometry/Outline")
		(27 "Margin" user)
		(31 "F.CrtYd" user "Package Geometry/Place Bound Top")
		(29 "B.CrtYd" user "Package Geometry/Place Bound Bottom")
		(35 "F.Fab" user "Ref Des/Assembly Top")
		(33 "B.Fab" user "Ref Des/Assembly Bottom")
	)
	(footprint ""
		(layer "F.Cu")
		(at 11.502644 5.004562 -90)
		(property "Reference" "R12W15"
			(at 0 0 270)
			(layer "F.SilkS")
			(hide yes)
			(effects
				(font
					(size 1.27 1.27)
				)
			)
		)
		(property "Value" "*"
			(at 0.064008 -4.108196 270)
			(unlocked yes)
			(layer "F.Fab")
			(hide yes)
			(effects
				(font
					(size 1.27 1.016)
					(thickness 0.1524)
				)
			)
		)
		(property "Device Type" "665KR2B-GP_SMD-RG2-665KR2B-GP,A"
			(at 0.064008 -5.632196 270)
			(unlocked yes)
			(layer "F.Fab")
			(hide yes)
			(effects
				(font
					(size 1.27 1.016)
					(thickness 0.1524)
				)
			)
		)
		(duplicate_pad_numbers_are_jumpers no)
		(fp_line
			(start -0.508 -0.9398)
			(end -0.508 0.9398)
			(stroke
				(width 0.1524)
				(type default)
			)
			(layer "F.SilkS")
		)
		(fp_line
			(start 0.508 -0.9398)
			(end -0.508 -0.9398)
			(stroke
				(width 0.1524)
				(type default)
			)
			(layer "F.SilkS")
		)
		(fp_rect
			(start -0.508 0.9398)
			(end 0.508 -0.9398)
			(stroke
				(width 0)
				(type default)
			)
			(fill no)
			(layer "F.CrtYd")
		)
		(fp_rect
			(start -0.508 0.9398)
			(end 0.508 -0.9398)
			(stroke
				(width 0)
				(type default)
			)
			(fill no)
			(layer "F.Fab")
		)
		(pad "1" smd custom
			(at 0 -0.4445 270)
			(size 0.1397 0.1397)
			(layers "F.Cu" "F.Mask" "F.Paste")
			(net "VR_PVDDQ_GHJ_AIINSEN")
			(options
				(clearance outline)
				(anchor circle)
			)
			(primitives
				(gr_poly
					(pts
						(arc
							(start -0.1778 -0.2794)
							(mid -0.249642 -0.249642)
							(end -0.2794 -0.1778)
						)
						(arc
							(start -0.2794 0.1778)
							(mid -0.249642 0.249642)
							(end -0.1778 0.2794)
						)
						(arc
							(start 0.1778 0.2794)
							(mid 0.249642 0.249642)
							(end 0.2794 0.1778)
						)
						(arc
							(start 0.2794 -0.1778)
							(mid 0.249642 -0.249642)
							(end 0.1778 -0.2794)
						)
					)
					(width 0)
					(fill yes)
				)
			)
		)
		(pad "2" smd custom
			(at 0 0.4445 270)
			(size 0.1397 0.1397)
			(layers "F.Cu" "F.Mask" "F.Paste")
			(net "VR_PVDDQ_GHJ_VINSEN")
			(options
				(clearance outline)
				(anchor circle)
			)
			(primitives
				(gr_poly
					(pts
						(arc
							(start -0.1778 -0.2794)
							(mid -0.249642 -0.249642)
							(end -0.2794 -0.1778)
						)
						(arc
							(start -0.2794 0.1778)
							(mid -0.249642 0.249642)
							(end -0.1778 0.2794)
						)
						(arc
							(start 0.1778 0.2794)
							(mid 0.249642 0.249642)
							(end 0.2794 0.1778)
						)
						(arc
							(start 0.2794 -0.1778)
							(mid 0.249642 -0.249642)
							(end 0.1778 -0.2794)
						)
					)
					(width 0)
					(fill yes)
				)
			)
		)
	)
	(footprint ""
		(layer "F.Cu")
		(at 1.133094 -123.20905 90)
		(property "Reference" "CF22"
			(at 0 0 90)
			(layer "F.SilkS")
			(hide yes)
			(effects
				(font
					(size 1.27 1.27)
				)
			)
		)
		(property "Value" "*"
			(at 1.1811 -2.8194 90)
			(unlocked yes)
			(layer "F.Fab")
			(hide yes)
			(effects
				(font
					(size 1.27 1.016)
					(thickness 0.1524)
				)
			)
		)
		(property "Device Type" "SC22P50V2JN-4GP_SMD-BCG-SC22P5A"
			(at 1.1811 -4.3434 90)
			(unlocked yes)
			(layer "F.Fab")
			(hide yes)
			(effects
				(font
					(size 1.27 1.016)
					(thickness 0.1524)
				)
			)
		)
		(duplicate_pad_numbers_are_jumpers no)
		(fp_rect
			(start -0.4318 0.9525)
			(end 0.4318 -0.9525)
			(stroke
				(width 0)
				(type default)
			)
			(fill no)
			(layer "F.CrtYd")
		)
		(fp_rect
			(start -0.4318 0.9525)
			(end 0.4318 -0.9525)
			(stroke
				(width 0)
				(type default)
			)
			(fill no)
			(layer "F.Fab")
		)
		(pad "1" smd custom
			(at 0 -0.4445 90)
			(size 0.1524 0.1524)
			(layers "F.Cu" "F.Mask" "F.Paste")
			(net "VR_PVDDQ_KLM_AIREF2")
			(options
				(clearance outline)
				(anchor circle)
			)
			(primitives
				(gr_poly
					(pts
						(arc
							(start 0.3048 -0.2032)
							(mid 0.275042 -0.275042)
							(end 0.2032 -0.3048)
						)
						(arc
							(start -0.2032 -0.3048)
							(mid -0.275042 -0.275042)
							(end -0.3048 -0.2032)
						)
						(arc
							(start -0.3048 0.2032)
							(mid -0.275042 0.275042)
							(end -0.2032 0.3048)
						)
						(arc
							(start 0.2032 0.3048)
							(mid 0.275042 0.275042)
							(end 0.3048 0.2032)
						)
					)
					(width 0)
					(fill yes)
				)
			)
		)
		(pad "2" smd custom
			(at 0 0.4445 90)
			(size 0.1524 0.1524)
			(layers "F.Cu" "F.Mask" "F.Paste")
			(net "ISENSE_PVDDQ_KLM_PH2_IMON")
			(options
				(clearance outline)
				(anchor circle)
			)
			(primitives
				(gr_poly
					(pts
						(arc
							(start 0.3048 -0.2032)
							(mid 0.275042 -0.275042)
							(end 0.2032 -0.3048)
						)
						(arc
							(start -0.2032 -0.3048)
							(mid -0.275042 -0.275042)
							(end -0.3048 -0.2032)
						)
						(arc
							(start -0.3048 0.2032)
							(mid -0.275042 0.275042)
							(end -0.2032 0.3048)
						)
						(arc
							(start 0.2032 0.3048)
							(mid 0.275042 0.275042)
							(end 0.3048 0.2032)
						)
					)
					(width 0)
					(fill yes)
				)
			)
		)
	)
	(footprint ""
		(layer "F.Cu")
		(at 386.1054 -0.254)
		(property "Reference" "R7G17"
			(at 0 0 0)
			(layer "F.SilkS")
			(hide yes)
			(effects
				(font
					(size 1.27 1.27)
				)
			)
		)
		(property "Value" ""
			(at 0 0 0)
			(layer "F.Fab")
			(effects
				(font
					(size 1.27 1.27)
				)
			)
		)
		(duplicate_pad_numbers_are_jumpers no)
		(fp_poly
			(pts
				(xy -0.2794 -0.1016) (xy 0.2794 -0.1016) (xy 0.2794 0.9906) (xy -0.2794 0.9906)
			)
			(stroke
				(width 0)
				(type default)
			)
			(fill no)
			(layer "F.CrtYd")
		)
		(fp_line
			(start -0.2794 -0.1016)
			(end -0.2794 0.9906)
			(stroke
				(width 0.1)
				(type default)
			)
			(layer "F.Fab")
		)
		(fp_line
			(start -0.2794 0.9906)
			(end 0.2794 0.9906)
			(stroke
				(width 0.1)
				(type default)
			)
			(layer "F.Fab")
		)
		(fp_line
			(start 0.2794 -0.1016)
			(end -0.2794 -0.1016)
			(stroke
				(width 0.1)
				(type default)
			)
			(layer "F.Fab")
		)
		(fp_line
			(start 0.2794 0.9906)
			(end 0.2794 -0.1016)
			(stroke
				(width 0.1)
				(type default)
			)
			(layer "F.Fab")
		)
		(pad "1" smd rect
			(at 0 0)
			(size 0.508 0.508)
			(layers "F.Cu" "F.Mask" "F.Paste")
			(net "JTAG_BMC_TDO")
		)
		(pad "2" smd rect
			(at 0 0.889)
			(size 0.508 0.508)
			(layers "F.Cu" "F.Mask" "F.Paste")
			(net "JTAG_TDO")
		)
		(zone
			(layer "F.Cu")
			(hatch none 0.5)
			(connect_pads
				(clearance 0)
			)
			(min_thickness 0.25)
			(keepout
				(tracks allowed)
				(vias not_allowed)
				(pads allowed)
				(copperpour not_allowed)
				(footprints allowed)
			)
			(placement
				(enabled no)
				(sheetname "")
			)
			(fill
				(thermal_gap 0.5)
				(thermal_bridge_width 0.5)
				(island_removal_mode 0)
			)
			(polygon
				(pts
					(xy 385.8514 0) (xy 386.3594 0) (xy 386.3594 0.381) (xy 385.8514 0.381)
				)
			)
		)
		(zone
			(layer "F.Cu")
			(hatch none 0.5)
			(connect_pads
				(clearance 0)
			)
			(min_thickness 0.25)
			(keepout
				(tracks not_allowed)
				(vias allowed)
				(pads allowed)
				(copperpour not_allowed)
				(footprints allowed)
			)
			(placement
				(enabled no)
				(sheetname "")
			)
			(fill
				(thermal_gap 0.5)
				(thermal_bridge_width 0.5)
				(island_removal_mode 0)
			)
			(polygon
				(pts
					(xy 385.8514 0.381) (xy 386.3594 0.381) (xy 386.3594 0) (xy 385.8514 0)
				)
			)
		)
	)
)
